# S9S_MB_2U (Grand Teton) — schematic netlist excerpt (pin names and nets, part order shuffled) for the footprints in the layout excerpt that follows; sources: Cadence DE-HDL packaged netlist, KiCad conversion of 03242023_DA0F0TMBIJ0_F0T_Motherboard_J_brd_V01_OCP.brd

PJ65  Q_SHORT  EMPTY  pkg SM  page 281 : \1\ = SH_PVPP_HBM_CPU0_N ; \2\ = GND
C1866  Q_CAP  0.1UF 25V 10% X7R  pkg 0402  page 166 : A = P3V3_AUX ; B = GND
PR678  Q_RES  0 5% CHIP  pkg 0402LF  page 294 : A = P5V ; B = PVCCFA_EHV_CPU1_PVCC

(kicad_pcb
	(version 20260206)
	(generator "pcbnew")
	(generator_version "10.0")
	(general
		(thickness 1.6)
		(legacy_teardrops no)
	)
	(paper "A4")
	(title_block
		(title "03242023_DA0F0TMBIJ0_F0T_Motherboard_J_brd_V01_OCP.brd")
		(comment 1 "Grand Teton / footprints 5758-5760 of 6105")
	)
	(layers
		(0 "F.Cu" signal "TOP")
		(4 "In1.Cu" signal "GND")
		(6 "In2.Cu" signal "IN1")
		(8 "In3.Cu" signal "GND1")
		(10 "In4.Cu" signal "IN2")
		(12 "In5.Cu" signal "GND2")
		(14 "In6.Cu" signal "IN3")
		(16 "In7.Cu" signal "GND3")
		(18 "In8.Cu" signal "VCC")
		(20 "In9.Cu" signal "VCC1")
		(22 "In10.Cu" signal "GND4")
		(24 "In11.Cu" signal "IN4")
		(26 "In12.Cu" signal "GND5")
		(28 "In13.Cu" signal "IN5")
		(30 "In14.Cu" signal "GND6")
		(32 "In15.Cu" signal "IN6")
		(34 "In16.Cu" signal "GND7")
		(2 "B.Cu" signal "BOTTOM")
		(9 "F.Adhes" user "F.Adhesive")
		(11 "B.Adhes" user "B.Adhesive")
		(13 "F.Paste" user "Package Geometry/Pastemask Top")
		(15 "B.Paste" user "Package Geometry/Pastemask Bottom")
		(5 "F.SilkS" user "Ref Des/Silkscreen Top")
		(7 "B.SilkS" user "Ref Des/Silkscreen Bottom")
		(1 "F.Mask" user "Board Geometry/Soldermask Top")
		(3 "B.Mask" user "Board Geometry/Soldermask Bottom")
		(17 "Dwgs.User" user "User.Drawings")
		(19 "Cmts.User" user "User.Comments")
		(21 "Eco1.User" user "User.Eco1")
		(23 "Eco2.User" user "User.Eco2")
		(25 "Edge.Cuts" user "Board Geometry/Outline")
		(27 "Margin" user)
		(31 "F.CrtYd" user "Package Geometry/Place Bound Top")
		(29 "B.CrtYd" user "Package Geometry/Place Bound Bottom")
		(35 "F.Fab" user "Ref Des/Assembly Top")
		(33 "B.Fab" user "Ref Des/Assembly Bottom")
	)
	(footprint ""
		(layer "B.Cu")
		(at 38.420548 -392.686286 180)
		(property "Reference" "C1866"
			(at 0 0 0)
			(layer "B.SilkS")
			(hide yes)
			(effects
				(font
					(size 1.27 1.27)
				)
				(justify mirror)
			)
		)
		(property "Value" ""
			(at 0 0 0)
			(layer "B.Fab")
			(effects
				(font
					(size 1.27 1.27)
				)
				(justify mirror)
			)
		)
		(duplicate_pad_numbers_are_jumpers no)
		(fp_line
			(start 0.7874 0.4064)
			(end 0.7874 -0.4064)
			(stroke
				(width 0.1524)
				(type default)
			)
			(layer "B.SilkS")
		)
		(fp_line
			(start 0.7874 -0.4064)
			(end -0.7874 -0.4064)
			(stroke
				(width 0.1524)
				(type default)
			)
			(layer "B.SilkS")
		)
		(fp_line
			(start -0.7874 0.4064)
			(end 0.7874 0.4064)
			(stroke
				(width 0.1524)
				(type default)
			)
			(layer "B.SilkS")
		)
		(fp_line
			(start -0.7874 -0.4064)
			(end -0.7874 0.4064)
			(stroke
				(width 0.1524)
				(type default)
			)
			(layer "B.SilkS")
		)
		(fp_line
			(start 0.67945 0.3048)
			(end 0.67945 -0.305054)
			(stroke
				(width 0.1)
				(type default)
			)
			(layer "B.Fab")
		)
		(fp_line
			(start 0.67945 -0.305054)
			(end 0.12065 -0.305054)
			(stroke
				(width 0.1)
				(type default)
			)
			(layer "B.Fab")
		)
		(fp_line
			(start 0.12065 0.3048)
			(end 0.67945 0.3048)
			(stroke
				(width 0.1)
				(type default)
			)
			(layer "B.Fab")
		)
		(fp_line
			(start 0.12065 0.2794)
			(end 0.12065 0.3048)
			(stroke
				(width 0.1)
				(type default)
			)
			(layer "B.Fab")
		)
		(fp_line
			(start 0.12065 -0.2794)
			(end -0.12065 -0.2794)
			(stroke
				(width 0.1)
				(type default)
			)
			(layer "B.Fab")
		)
		(fp_line
			(start 0.12065 -0.305054)
			(end 0.12065 -0.2794)
			(stroke
				(width 0.1)
				(type default)
			)
			(layer "B.Fab")
		)
		(fp_line
			(start -0.120396 0.3048)
			(end -0.120396 0.2794)
			(stroke
				(width 0.1)
				(type default)
			)
			(layer "B.Fab")
		)
		(fp_line
			(start -0.120396 0.2794)
			(end 0.12065 0.2794)
			(stroke
				(width 0.1)
				(type default)
			)
			(layer "B.Fab")
		)
		(fp_line
			(start -0.12065 -0.2794)
			(end -0.12065 -0.3048)
			(stroke
				(width 0.1)
				(type default)
			)
			(layer "B.Fab")
		)
		(fp_line
			(start -0.12065 -0.3048)
			(end -0.67945 -0.3048)
			(stroke
				(width 0.1)
				(type default)
			)
			(layer "B.Fab")
		)
		(fp_line
			(start -0.67945 0.3048)
			(end -0.120396 0.3048)
			(stroke
				(width 0.1)
				(type default)
			)
			(layer "B.Fab")
		)
		(fp_line
			(start -0.67945 -0.3048)
			(end -0.67945 0.3048)
			(stroke
				(width 0.1)
				(type default)
			)
			(layer "B.Fab")
		)
		(pad "1" smd circle
			(at 0.40005 0)
			(size 0 0)
			(layers "B.Cu" "B.Mask" "B.Paste")
			(net "P3V3_AUX")
		)
		(pad "2" smd circle
			(at -0.40005 0)
			(size 0 0)
			(layers "B.Cu" "B.Mask" "B.Paste")
			(net "GND")
		)
	)
	(footprint ""
		(layer "B.Cu")
		(at 369.769898 -359.586276 -90)
		(property "Reference" "PJ65"
			(at -4.651502 -2.444242 0)
			(unlocked yes)
			(layer "B.SilkS")
			(effects
				(font
					(size 0.7874 0.5842)
					(thickness 0.1524)
				)
				(justify left mirror)
			)
		)
		(property "Value" ""
			(at 0 0 90)
			(layer "B.Fab")
			(effects
				(font
					(size 1.27 1.27)
				)
				(justify mirror)
			)
		)
		(duplicate_pad_numbers_are_jumpers no)
		(pad "1" smd circle
			(at 0.7493 0)
			(size 0 0)
			(layers "B.Cu" "B.Mask" "B.Paste")
			(net "SH_PVPP_HBM_CPU0_N")
		)
		(pad "2" smd rect
			(at -0.7493 0 180)
			(size 0.7112 0.8128)
			(layers "B.Cu" "B.Mask" "B.Paste")
			(net "GND")
		)
		(zone
			(layer "B.Cu")
			(hatch none 0.5)
			(connect_pads
				(clearance 0)
			)
			(min_thickness 0.25)
			(keepout
				(tracks allowed)
				(vias not_allowed)
				(pads allowed)
				(copperpour not_allowed)
				(footprints allowed)
			)
			(placement
				(enabled no)
				(sheetname "")
			)
			(fill
				(thermal_gap 0.5)
				(thermal_bridge_width 0.5)
				(island_removal_mode 0)
			)
			(polygon
				(pts
					(xy 369.358672 -358.405176) (xy 370.176298 -358.405176) (xy 370.176298 -360.792776) (xy 369.358672 -360.792776)
				)
			)
		)
	)
	(footprint ""
		(layer "B.Cu")
		(at 52.15128 -171.541948 -90)
		(property "Reference" "PR678"
			(at 0 0 90)
			(layer "B.SilkS")
			(hide yes)
			(effects
				(font
					(size 1.27 1.27)
				)
				(justify mirror)
			)
		)
		(property "Value" ""
			(at 0 0 90)
			(layer "B.Fab")
			(effects
				(font
					(size 1.27 1.27)
				)
				(justify mirror)
			)
		)
		(duplicate_pad_numbers_are_jumpers no)
		(fp_line
			(start -0.7874 0.4064)
			(end 0.7874 0.4064)
			(stroke
				(width 0.1524)
				(type default)
			)
			(layer "B.SilkS")
		)
		(fp_line
			(start 0.7874 0.4064)
			(end 0.7874 -0.4064)
			(stroke
				(width 0.1524)
				(type default)
			)
			(layer "B.SilkS")
		)
		(fp_line
			(start -0.7874 -0.4064)
			(end -0.7874 0.4064)
			(stroke
				(width 0.1524)
				(type default)
			)
			(layer "B.SilkS")
		)
		(fp_line
			(start 0.7874 -0.4064)
			(end -0.7874 -0.4064)
			(stroke
				(width 0.1524)
				(type default)
			)
			(layer "B.SilkS")
		)
		(fp_line
			(start -0.67945 0.3048)
			(end -0.120396 0.3048)
			(stroke
				(width 0.1)
				(type default)
			)
			(layer "B.Fab")
		)
		(fp_line
			(start -0.120396 0.3048)
			(end -0.120396 0.2794)
			(stroke
				(width 0.1)
				(type default)
			)
			(layer "B.Fab")
		)
		(fp_line
			(start 0.12065 0.3048)
			(end 0.67945 0.3048)
			(stroke
				(width 0.1)
				(type default)
			)
			(layer "B.Fab")
		)
		(fp_line
			(start 0.67945 0.3048)
			(end 0.67945 -0.305054)
			(stroke
				(width 0.1)
				(type default)
			)
			(layer "B.Fab")
		)
		(fp_line
			(start -0.120396 0.2794)
			(end 0.12065 0.2794)
			(stroke
				(width 0.1)
				(type default)
			)
			(layer "B.Fab")
		)
		(fp_line
			(start 0.12065 0.2794)
			(end 0.12065 0.3048)
			(stroke
				(width 0.1)
				(type default)
			)
			(layer "B.Fab")
		)
		(fp_line
			(start -0.12065 -0.2794)
			(end -0.12065 -0.3048)
			(stroke
				(width 0.1)
				(type default)
			)
			(layer "B.Fab")
		)
		(fp_line
			(start 0.12065 -0.2794)
			(end -0.12065 -0.2794)
			(stroke
				(width 0.1)
				(type default)
			)
			(layer "B.Fab")
		)
		(fp_line
			(start -0.67945 -0.3048)
			(end -0.67945 0.3048)
			(stroke
				(width 0.1)
				(type default)
			)
			(layer "B.Fab")
		)
		(fp_line
			(start -0.12065 -0.3048)
			(end -0.67945 -0.3048)
			(stroke
				(width 0.1)
				(type default)
			)
			(layer "B.Fab")
		)
		(fp_line
			(start 0.12065 -0.305054)
			(end 0.12065 -0.2794)
			(stroke
				(width 0.1)
				(type default)
			)
			(layer "B.Fab")
		)
		(fp_line
			(start 0.67945 -0.305054)
			(end 0.12065 -0.305054)
			(stroke
				(width 0.1)
				(type default)
			)
			(layer "B.Fab")
		)
		(pad "1" smd circle
			(at 0.40005 0 90)
			(size 0 0)
			(layers "B.Cu" "B.Mask" "B.Paste")
			(net "P5V")
		)
		(pad "2" smd circle
			(at -0.40005 0 90)
			(size 0 0)
			(layers "B.Cu" "B.Mask" "B.Paste")
			(net "PVCCFA_EHV_CPU1_PVCC")
		)
	)
)
